(kicad_pcb
	(version 20260206)
	(generator "pcbnew")
	(generator_version "10.0")
	(general
		(thickness 1.6)
		(legacy_teardrops no)
	)
	(paper "A4")
	(title_block
		(title "04192023_DAF0TMB3IC0_F0TG_MB_C_brd_V02_OCP.brd")
		(comment 1 "Grand Teton / footprints 3162-3165 of 8354")
	)
	(layers
		(0 "F.Cu" signal "TOP")
		(4 "In1.Cu" signal "GND")
		(6 "In2.Cu" signal "IN1")
		(8 "In3.Cu" signal "GND1")
		(10 "In4.Cu" signal "IN2")
		(12 "In5.Cu" signal "GND2")
		(14 "In6.Cu" signal "IN3")
		(16 "In7.Cu" signal "GND3")
		(18 "In8.Cu" signal "VCC")
		(20 "In9.Cu" signal "VCC1")
		(22 "In10.Cu" signal "GND4")
		(24 "In11.Cu" signal "IN4")
		(26 "In12.Cu" signal "GND5")
		(28 "In13.Cu" signal "IN5")
		(30 "In14.Cu" signal "GND6")
		(32 "In15.Cu" signal "IN6")
		(34 "In16.Cu" signal "GND7")
		(2 "B.Cu" signal "BOTTOM")
		(9 "F.Adhes" user "F.Adhesive")
		(11 "B.Adhes" user "B.Adhesive")
		(13 "F.Paste" user "Package Geometry/Pastemask Top")
		(15 "B.Paste" user "Package Geometry/Pastemask Bottom")
		(5 "F.SilkS" user "Ref Des/Silkscreen Top")
		(7 "B.SilkS" user "Ref Des/Silkscreen Bottom")
		(1 "F.Mask" user "Board Geometry/Soldermask Top")
		(3 "B.Mask" user "Board Geometry/Soldermask Bottom")
		(17 "Dwgs.User" user "User.Drawings")
		(19 "Cmts.User" user "User.Comments")
		(21 "Eco1.User" user "User.Eco1")
		(23 "Eco2.User" user "User.Eco2")
		(25 "Edge.Cuts" user "Board Geometry/Outline")
		(27 "Margin" user)
		(31 "F.CrtYd" user "Package Geometry/Place Bound Top")
		(29 "B.CrtYd" user "Package Geometry/Place Bound Bottom")
		(35 "F.Fab" user "Ref Des/Assembly Top")
		(33 "B.Fab" user "Ref Des/Assembly Bottom")
	)
	(footprint ""
		(layer "F.Cu")
		(at 120.69826 -29.373576)
		(property "Reference" "R6267"
			(at 0 0 0)
			(layer "F.SilkS")
			(hide yes)
			(effects
				(font
					(size 1.27 1.27)
				)
			)
		)
		(property "Value" ""
			(at 0 0 0)
			(layer "F.Fab")
			(effects
				(font
					(size 1.27 1.27)
				)
			)
		)
		(duplicate_pad_numbers_are_jumpers no)
		(fp_line
			(start -0.7874 -0.4064)
			(end 0.7874 -0.4064)
			(stroke
				(width 0.1524)
				(type default)
			)
			(layer "F.SilkS")
		)
		(fp_line
			(start -0.7874 0.4064)
			(end -0.7874 -0.4064)
			(stroke
				(width 0.1524)
				(type default)
			)
			(layer "F.SilkS")
		)
		(fp_line
			(start 0.7874 -0.4064)
			(end 0.7874 0.4064)
			(stroke
				(width 0.1524)
				(type default)
			)
			(layer "F.SilkS")
		)
		(fp_line
			(start 0.7874 0.4064)
			(end -0.7874 0.4064)
			(stroke
				(width 0.1524)
				(type default)
			)
			(layer "F.SilkS")
		)
		(fp_line
			(start -0.67945 -0.305054)
			(end -0.12065 -0.305054)
			(stroke
				(width 0.1)
				(type default)
			)
			(layer "F.Fab")
		)
		(fp_line
			(start -0.67945 0.3048)
			(end -0.67945 -0.305054)
			(stroke
				(width 0.1)
				(type default)
			)
			(layer "F.Fab")
		)
		(fp_line
			(start -0.12065 -0.305054)
			(end -0.12065 -0.2794)
			(stroke
				(width 0.1)
				(type default)
			)
			(layer "F.Fab")
		)
		(fp_line
			(start -0.12065 -0.2794)
			(end 0.12065 -0.2794)
			(stroke
				(width 0.1)
				(type default)
			)
			(layer "F.Fab")
		)
		(fp_line
			(start -0.12065 0.2794)
			(end -0.12065 0.3048)
			(stroke
				(width 0.1)
				(type default)
			)
			(layer "F.Fab")
		)
		(fp_line
			(start -0.12065 0.3048)
			(end -0.67945 0.3048)
			(stroke
				(width 0.1)
				(type default)
			)
			(layer "F.Fab")
		)
		(fp_line
			(start 0.120396 0.2794)
			(end -0.12065 0.2794)
			(stroke
				(width 0.1)
				(type default)
			)
			(layer "F.Fab")
		)
		(fp_line
			(start 0.120396 0.3048)
			(end 0.120396 0.2794)
			(stroke
				(width 0.1)
				(type default)
			)
			(layer "F.Fab")
		)
		(fp_line
			(start 0.12065 -0.3048)
			(end 0.67945 -0.3048)
			(stroke
				(width 0.1)
				(type default)
			)
			(layer "F.Fab")
		)
		(fp_line
			(start 0.12065 -0.2794)
			(end 0.12065 -0.3048)
			(stroke
				(width 0.1)
				(type default)
			)
			(layer "F.Fab")
		)
		(fp_line
			(start 0.67945 -0.3048)
			(end 0.67945 0.3048)
			(stroke
				(width 0.1)
				(type default)
			)
			(layer "F.Fab")
		)
		(fp_line
			(start 0.67945 0.3048)
			(end 0.120396 0.3048)
			(stroke
				(width 0.1)
				(type default)
			)
			(layer "F.Fab")
		)
		(pad "1" smd circle
			(at -0.40005 0)
			(size 0 0)
			(layers "F.Cu" "F.Mask" "F.Paste")
			(net "USB_HUB2_TI_VDD_MRP_USB3DN_TXDP4")
		)
		(pad "2" smd circle
			(at 0.40005 0)
			(size 0 0)
			(layers "F.Cu" "F.Mask" "F.Paste")
			(net "P1V2_CPU0_USB2_DVDD12")
		)
	)
	(footprint ""
		(layer "F.Cu")
		(at 126.804928 -47.121064)
		(property "Reference" "R6205"
			(at 0 0 0)
			(layer "F.SilkS")
			(hide yes)
			(effects
				(font
					(size 1.27 1.27)
				)
			)
		)
		(property "Value" ""
			(at 0 0 0)
			(layer "F.Fab")
			(effects
				(font
					(size 1.27 1.27)
				)
			)
		)
		(duplicate_pad_numbers_are_jumpers no)
		(fp_line
			(start -0.7874 -0.4064)
			(end 0.7874 -0.4064)
			(stroke
				(width 0.1524)
				(type default)
			)
			(layer "F.SilkS")
		)
		(fp_line
			(start -0.7874 0.4064)
			(end -0.7874 -0.4064)
			(stroke
				(width 0.1524)
				(type default)
			)
			(layer "F.SilkS")
		)
		(fp_line
			(start 0.7874 -0.4064)
			(end 0.7874 0.4064)
			(stroke
				(width 0.1524)
				(type default)
			)
			(layer "F.SilkS")
		)
		(fp_line
			(start 0.7874 0.4064)
			(end -0.7874 0.4064)
			(stroke
				(width 0.1524)
				(type default)
			)
			(layer "F.SilkS")
		)
		(fp_line
			(start -0.67945 -0.305054)
			(end -0.12065 -0.305054)
			(stroke
				(width 0.1)
				(type default)
			)
			(layer "F.Fab")
		)
		(fp_line
			(start -0.67945 0.3048)
			(end -0.67945 -0.305054)
			(stroke
				(width 0.1)
				(type default)
			)
			(layer "F.Fab")
		)
		(fp_line
			(start -0.12065 -0.305054)
			(end -0.12065 -0.2794)
			(stroke
				(width 0.1)
				(type default)
			)
			(layer "F.Fab")
		)
		(fp_line
			(start -0.12065 -0.2794)
			(end 0.12065 -0.2794)
			(stroke
				(width 0.1)
				(type default)
			)
			(layer "F.Fab")
		)
		(fp_line
			(start -0.12065 0.2794)
			(end -0.12065 0.3048)
			(stroke
				(width 0.1)
				(type default)
			)
			(layer "F.Fab")
		)
		(fp_line
			(start -0.12065 0.3048)
			(end -0.67945 0.3048)
			(stroke
				(width 0.1)
				(type default)
			)
			(layer "F.Fab")
		)
		(fp_line
			(start 0.120396 0.2794)
			(end -0.12065 0.2794)
			(stroke
				(width 0.1)
				(type default)
			)
			(layer "F.Fab")
		)
		(fp_line
			(start 0.120396 0.3048)
			(end 0.120396 0.2794)
			(stroke
				(width 0.1)
				(type default)
			)
			(layer "F.Fab")
		)
		(fp_line
			(start 0.12065 -0.3048)
			(end 0.67945 -0.3048)
			(stroke
				(width 0.1)
				(type default)
			)
			(layer "F.Fab")
		)
		(fp_line
			(start 0.12065 -0.2794)
			(end 0.12065 -0.3048)
			(stroke
				(width 0.1)
				(type default)
			)
			(layer "F.Fab")
		)
		(fp_line
			(start 0.67945 -0.3048)
			(end 0.67945 0.3048)
			(stroke
				(width 0.1)
				(type default)
			)
			(layer "F.Fab")
		)
		(fp_line
			(start 0.67945 0.3048)
			(end 0.120396 0.3048)
			(stroke
				(width 0.1)
				(type default)
			)
			(layer "F.Fab")
		)
		(pad "1" smd circle
			(at -0.40005 0)
			(size 0 0)
			(layers "F.Cu" "F.Mask" "F.Paste")
			(net "P3V3_AUX")
		)
		(pad "2" smd circle
			(at 0.40005 0)
			(size 0 0)
			(layers "F.Cu" "F.Mask" "F.Paste")
			(net "PU_CPU0_USB_HUB_OVRCURR")
		)
	)
	(footprint ""
		(layer "F.Cu")
		(at 453.719946 -104.249728)
		(property "Reference" "R1906"
			(at 0 0 0)
			(layer "F.SilkS")
			(hide yes)
			(effects
				(font
					(size 1.27 1.27)
				)
			)
		)
		(property "Value" ""
			(at 0 0 0)
			(layer "F.Fab")
			(effects
				(font
					(size 1.27 1.27)
				)
			)
		)
		(duplicate_pad_numbers_are_jumpers no)
		(fp_line
			(start -0.7874 -0.4064)
			(end 0.7874 -0.4064)
			(stroke
				(width 0.1524)
				(type default)
			)
			(layer "F.SilkS")
		)
		(fp_line
			(start -0.7874 0.4064)
			(end -0.7874 -0.4064)
			(stroke
				(width 0.1524)
				(type default)
			)
			(layer "F.SilkS")
		)
		(fp_line
			(start 0.7874 -0.4064)
			(end 0.7874 0.4064)
			(stroke
				(width 0.1524)
				(type default)
			)
			(layer "F.SilkS")
		)
		(fp_line
			(start 0.7874 0.4064)
			(end -0.7874 0.4064)
			(stroke
				(width 0.1524)
				(type default)
			)
			(layer "F.SilkS")
		)
		(fp_line
			(start -0.67945 -0.305054)
			(end -0.12065 -0.305054)
			(stroke
				(width 0.1)
				(type default)
			)
			(layer "F.Fab")
		)
		(fp_line
			(start -0.67945 0.3048)
			(end -0.67945 -0.305054)
			(stroke
				(width 0.1)
				(type default)
			)
			(layer "F.Fab")
		)
		(fp_line
			(start -0.12065 -0.305054)
			(end -0.12065 -0.2794)
			(stroke
				(width 0.1)
				(type default)
			)
			(layer "F.Fab")
		)
		(fp_line
			(start -0.12065 -0.2794)
			(end 0.12065 -0.2794)
			(stroke
				(width 0.1)
				(type default)
			)
			(layer "F.Fab")
		)
		(fp_line
			(start -0.12065 0.2794)
			(end -0.12065 0.3048)
			(stroke
				(width 0.1)
				(type default)
			)
			(layer "F.Fab")
		)
		(fp_line
			(start -0.12065 0.3048)
			(end -0.67945 0.3048)
			(stroke
				(width 0.1)
				(type default)
			)
			(layer "F.Fab")
		)
		(fp_line
			(start 0.120396 0.2794)
			(end -0.12065 0.2794)
			(stroke
				(width 0.1)
				(type default)
			)
			(layer "F.Fab")
		)
		(fp_line
			(start 0.120396 0.3048)
			(end 0.120396 0.2794)
			(stroke
				(width 0.1)
				(type default)
			)
			(layer "F.Fab")
		)
		(fp_line
			(start 0.12065 -0.3048)
			(end 0.67945 -0.3048)
			(stroke
				(width 0.1)
				(type default)
			)
			(layer "F.Fab")
		)
		(fp_line
			(start 0.12065 -0.2794)
			(end 0.12065 -0.3048)
			(stroke
				(width 0.1)
				(type default)
			)
			(layer "F.Fab")
		)
		(fp_line
			(start 0.67945 -0.3048)
			(end 0.67945 0.3048)
			(stroke
				(width 0.1)
				(type default)
			)
			(layer "F.Fab")
		)
		(fp_line
			(start 0.67945 0.3048)
			(end 0.120396 0.3048)
			(stroke
				(width 0.1)
				(type default)
			)
			(layer "F.Fab")
		)
		(pad "1" smd circle
			(at -0.40005 0)
			(size 0 0)
			(layers "F.Cu" "F.Mask" "F.Paste")
			(net "P3V3_AUX")
		)
		(pad "2" smd circle
			(at 0.40005 0)
			(size 0 0)
			(layers "F.Cu" "F.Mask" "F.Paste")
			(net "OCP_SFF_PRSNT2_R_N")
		)
	)
	(footprint ""
		(layer "F.Cu")
		(at 420.833296 -357.688134 -90)
		(property "Reference" "PR34"
			(at 0 0 270)
			(layer "F.SilkS")
			(hide yes)
			(effects
				(font
					(size 1.27 1.27)
				)
			)
		)
		(property "Value" ""
			(at 0 0 270)
			(layer "F.Fab")
			(effects
				(font
					(size 1.27 1.27)
				)
			)
		)
		(duplicate_pad_numbers_are_jumpers no)
		(fp_line
			(start -0.7874 0.4064)
			(end -0.7874 -0.4064)
			(stroke
				(width 0.1524)
				(type default)
			)
			(layer "F.SilkS")
		)
		(fp_line
			(start 0.7874 0.4064)
			(end -0.7874 0.4064)
			(stroke
				(width 0.1524)
				(type default)
			)
			(layer "F.SilkS")
		)
		(fp_line
			(start -0.7874 -0.4064)
			(end 0.7874 -0.4064)
			(stroke
				(width 0.1524)
				(type default)
			)
			(layer "F.SilkS")
		)
		(fp_line
			(start 0.7874 -0.4064)
			(end 0.7874 0.4064)
			(stroke
				(width 0.1524)
				(type default)
			)
			(layer "F.SilkS")
		)
		(fp_line
			(start -0.67945 0.3048)
			(end -0.67945 -0.305054)
			(stroke
				(width 0.1)
				(type default)
			)
			(layer "F.Fab")
		)
		(fp_line
			(start -0.12065 0.3048)
			(end -0.67945 0.3048)
			(stroke
				(width 0.1)
				(type default)
			)
			(layer "F.Fab")
		)
		(fp_line
			(start 0.120396 0.3048)
			(end 0.120396 0.2794)
			(stroke
				(width 0.1)
				(type default)
			)
			(layer "F.Fab")
		)
		(fp_line
			(start 0.67945 0.3048)
			(end 0.120396 0.3048)
			(stroke
				(width 0.1)
				(type default)
			)
			(layer "F.Fab")
		)
		(fp_line
			(start -0.12065 0.2794)
			(end -0.12065 0.3048)
			(stroke
				(width 0.1)
				(type default)
			)
			(layer "F.Fab")
		)
		(fp_line
			(start 0.120396 0.2794)
			(end -0.12065 0.2794)
			(stroke
				(width 0.1)
				(type default)
			)
			(layer "F.Fab")
		)
		(fp_line
			(start -0.12065 -0.2794)
			(end 0.12065 -0.2794)
			(stroke
				(width 0.1)
				(type default)
			)
			(layer "F.Fab")
		)
		(fp_line
			(start 0.12065 -0.2794)
			(end 0.12065 -0.3048)
			(stroke
				(width 0.1)
				(type default)
			)
			(layer "F.Fab")
		)
		(fp_line
			(start 0.12065 -0.3048)
			(end 0.67945 -0.3048)
			(stroke
				(width 0.1)
				(type default)
			)
			(layer "F.Fab")
		)
		(fp_line
			(start 0.67945 -0.3048)
			(end 0.67945 0.3048)
			(stroke
				(width 0.1)
				(type default)
			)
			(layer "F.Fab")
		)
		(fp_line
			(start -0.67945 -0.305054)
			(end -0.12065 -0.305054)
			(stroke
				(width 0.1)
				(type default)
			)
			(layer "F.Fab")
		)
		(fp_line
			(start -0.12065 -0.305054)
			(end -0.12065 -0.2794)
			(stroke
				(width 0.1)
				(type default)
			)
			(layer "F.Fab")
		)
		(pad "1" smd circle
			(at -0.40005 0 270)
			(size 0 0)
			(layers "F.Cu" "F.Mask" "F.Paste")
			(net "NC_PVDD11_S3_P0_IMON5")
		)
		(pad "2" smd circle
			(at 0.40005 0 270)
			(size 0 0)
			(layers "F.Cu" "F.Mask" "F.Paste")
			(net "GND")
		)
	)
)
